(kicad_pcb
	(version 20260206)
	(generator "pcbnew")
	(generator_version "10.0")
	(general
		(thickness 1.6)
		(legacy_teardrops no)
	)
	(paper "A4")
	(title_block
		(title "peb — Lightning_PEB_BRD.brd")
		(comment 1 "Lightning (Wiwynn / Facebook NVMe JBOF) / footprints 2030-2036 of 2563")
	)
	(layers
		(0 "F.Cu" signal "TOP")
		(4 "In1.Cu" signal "L2GND")
		(6 "In2.Cu" signal "L3")
		(8 "In3.Cu" signal "L4VCC")
		(10 "In4.Cu" signal "L5VCC")
		(12 "In5.Cu" signal "L6")
		(14 "In6.Cu" signal "L7GND")
		(2 "B.Cu" signal "BOTTOM")
		(9 "F.Adhes" user "F.Adhesive")
		(11 "B.Adhes" user "B.Adhesive")
		(13 "F.Paste" user "Package Geometry/Pastemask Top")
		(15 "B.Paste" user "Package Geometry/Pastemask Bottom")
		(5 "F.SilkS" user "Ref Des/Silkscreen Top")
		(7 "B.SilkS" user "Ref Des/Silkscreen Bottom")
		(1 "F.Mask" user "Board Geometry/Soldermask Top")
		(3 "B.Mask" user "Board Geometry/Soldermask Bottom")
		(17 "Dwgs.User" user "User.Drawings")
		(19 "Cmts.User" user "User.Comments")
		(21 "Eco1.User" user "User.Eco1")
		(23 "Eco2.User" user "User.Eco2")
		(25 "Edge.Cuts" user "Board Geometry/Outline")
		(27 "Margin" user)
		(31 "F.CrtYd" user "Package Geometry/Place Bound Top")
		(29 "B.CrtYd" user "Package Geometry/Place Bound Bottom")
		(35 "F.Fab" user "Ref Des/Assembly Top")
		(33 "B.Fab" user "Ref Des/Assembly Bottom")
	)
	(footprint ""
		(layer "B.Cu")
		(at 48.1711 -116.032788 180)
		(property "Reference" "R465"
			(at 0 0 0)
			(layer "B.SilkS")
			(hide yes)
			(effects
				(font
					(size 1.27 1.27)
				)
				(justify mirror)
			)
		)
		(property "Value" "0R2J-2-GP"
			(at -0.064008 -3.993896 180)
			(unlocked yes)
			(layer "B.Fab")
			(hide yes)
			(effects
				(font
					(size 1.016 1.016)
					(thickness 0.1524)
				)
				(justify mirror)
			)
		)
		(property "Device Type" "R402H16"
			(at -0.064008 -5.517896 180)
			(unlocked yes)
			(layer "B.Fab")
			(hide yes)
			(effects
				(font
					(size 1.016 1.016)
					(thickness 0.1524)
				)
				(justify mirror)
			)
		)
		(duplicate_pad_numbers_are_jumpers no)
		(fp_line
			(start 0.508 -0.9398)
			(end 0.508 0.9398)
			(stroke
				(width 0.1524)
				(type default)
			)
			(layer "B.SilkS")
		)
		(fp_line
			(start -0.508 -0.9398)
			(end 0.508 -0.9398)
			(stroke
				(width 0.1524)
				(type default)
			)
			(layer "B.SilkS")
		)
		(fp_rect
			(start 0.508 0.9398)
			(end -0.508 -0.9398)
			(stroke
				(width 0)
				(type default)
			)
			(fill no)
			(layer "B.CrtYd")
		)
		(fp_rect
			(start 0.508 0.9398)
			(end -0.508 -0.9398)
			(stroke
				(width 0)
				(type default)
			)
			(fill no)
			(layer "B.Fab")
		)
		(pad "1" smd custom
			(at 0 -0.4445)
			(size 0.1397 0.1397)
			(layers "B.Cu" "B.Mask" "B.Paste")
			(net "BMC_I2C9_CLKBUF2_SCL")
			(options
				(clearance outline)
				(anchor circle)
			)
			(primitives
				(gr_poly
					(pts
						(arc
							(start -0.1778 0.2794)
							(mid -0.249642 0.249642)
							(end -0.2794 0.1778)
						)
						(arc
							(start -0.2794 -0.1778)
							(mid -0.249642 -0.249642)
							(end -0.1778 -0.2794)
						)
						(arc
							(start 0.1778 -0.2794)
							(mid 0.249642 -0.249642)
							(end 0.2794 -0.1778)
						)
						(arc
							(start 0.2794 0.1778)
							(mid 0.249642 0.249642)
							(end 0.1778 0.2794)
						)
					)
					(width 0)
					(fill yes)
				)
			)
		)
		(pad "2" smd custom
			(at 0 0.4445)
			(size 0.1397 0.1397)
			(layers "B.Cu" "B.Mask" "B.Paste")
			(net "BMC0_SMB9_CLK")
			(options
				(clearance outline)
				(anchor circle)
			)
			(primitives
				(gr_poly
					(pts
						(arc
							(start -0.1778 0.2794)
							(mid -0.249642 0.249642)
							(end -0.2794 0.1778)
						)
						(arc
							(start -0.2794 -0.1778)
							(mid -0.249642 -0.249642)
							(end -0.1778 -0.2794)
						)
						(arc
							(start 0.1778 -0.2794)
							(mid 0.249642 -0.249642)
							(end 0.2794 -0.1778)
						)
						(arc
							(start 0.2794 0.1778)
							(mid 0.249642 0.249642)
							(end 0.1778 0.2794)
						)
					)
					(width 0)
					(fill yes)
				)
			)
		)
	)
	(footprint ""
		(layer "B.Cu")
		(at 271.4625 -6.6675)
		(property "Reference" "R371"
			(at 0 0 0)
			(layer "B.SilkS")
			(hide yes)
			(effects
				(font
					(size 1.27 1.27)
				)
				(justify mirror)
			)
		)
		(property "Value" "0R2J-2-GP"
			(at -0.064008 -3.993896 0)
			(unlocked yes)
			(layer "B.Fab")
			(hide yes)
			(effects
				(font
					(size 1.016 1.016)
					(thickness 0.1524)
				)
				(justify mirror)
			)
		)
		(property "Device Type" "R402H16"
			(at -0.064008 -5.517896 0)
			(unlocked yes)
			(layer "B.Fab")
			(hide yes)
			(effects
				(font
					(size 1.016 1.016)
					(thickness 0.1524)
				)
				(justify mirror)
			)
		)
		(duplicate_pad_numbers_are_jumpers no)
		(fp_line
			(start -0.508 -0.9398)
			(end 0.508 -0.9398)
			(stroke
				(width 0.1524)
				(type default)
			)
			(layer "B.SilkS")
		)
		(fp_line
			(start 0.508 -0.9398)
			(end 0.508 0.9398)
			(stroke
				(width 0.1524)
				(type default)
			)
			(layer "B.SilkS")
		)
		(fp_rect
			(start 0.508 0.9398)
			(end -0.508 -0.9398)
			(stroke
				(width 0)
				(type default)
			)
			(fill no)
			(layer "B.CrtYd")
		)
		(fp_rect
			(start 0.508 0.9398)
			(end -0.508 -0.9398)
			(stroke
				(width 0)
				(type default)
			)
			(fill no)
			(layer "B.Fab")
		)
		(pad "1" smd custom
			(at 0 -0.4445 180)
			(size 0.1397 0.1397)
			(layers "B.Cu" "B.Mask" "B.Paste")
			(net "CLK_P_7_R")
			(options
				(clearance outline)
				(anchor circle)
			)
			(primitives
				(gr_poly
					(pts
						(arc
							(start -0.1778 0.2794)
							(mid -0.249642 0.249642)
							(end -0.2794 0.1778)
						)
						(arc
							(start -0.2794 -0.1778)
							(mid -0.249642 -0.249642)
							(end -0.1778 -0.2794)
						)
						(arc
							(start 0.1778 -0.2794)
							(mid 0.249642 -0.249642)
							(end 0.2794 -0.1778)
						)
						(arc
							(start 0.2794 0.1778)
							(mid 0.249642 0.249642)
							(end 0.1778 0.2794)
						)
					)
					(width 0)
					(fill yes)
				)
			)
		)
		(pad "2" smd custom
			(at 0 0.4445 180)
			(size 0.1397 0.1397)
			(layers "B.Cu" "B.Mask" "B.Paste")
			(net "PCIE_REFCLK_H1_P_R")
			(options
				(clearance outline)
				(anchor circle)
			)
			(primitives
				(gr_poly
					(pts
						(arc
							(start -0.1778 0.2794)
							(mid -0.249642 0.249642)
							(end -0.2794 0.1778)
						)
						(arc
							(start -0.2794 -0.1778)
							(mid -0.249642 -0.249642)
							(end -0.1778 -0.2794)
						)
						(arc
							(start 0.1778 -0.2794)
							(mid 0.249642 -0.249642)
							(end 0.2794 -0.1778)
						)
						(arc
							(start 0.2794 0.1778)
							(mid 0.249642 0.249642)
							(end 0.1778 0.2794)
						)
					)
					(width 0)
					(fill yes)
				)
			)
		)
	)
	(footprint ""
		(layer "B.Cu")
		(at 41.660826 -132.51688 -90)
		(property "Reference" "C205"
			(at 0 0 90)
			(layer "B.SilkS")
			(hide yes)
			(effects
				(font
					(size 1.27 1.27)
				)
				(justify mirror)
			)
		)
		(property "Value" "SC1U10V2KX-4-GP"
			(at -1.1811 -2.7051 270)
			(unlocked yes)
			(layer "B.Fab")
			(hide yes)
			(effects
				(font
					(size 1.016 1.016)
					(thickness 0.1524)
				)
				(justify mirror)
			)
		)
		(property "Device Type" "C402H22"
			(at -1.1811 -4.2291 270)
			(unlocked yes)
			(layer "B.Fab")
			(hide yes)
			(effects
				(font
					(size 1.016 1.016)
					(thickness 0.1524)
				)
				(justify mirror)
			)
		)
		(duplicate_pad_numbers_are_jumpers no)
		(fp_rect
			(start 0.4318 0.9525)
			(end -0.4318 -0.9525)
			(stroke
				(width 0)
				(type default)
			)
			(fill no)
			(layer "B.CrtYd")
		)
		(fp_rect
			(start 0.4318 0.9525)
			(end -0.4318 -0.9525)
			(stroke
				(width 0)
				(type default)
			)
			(fill no)
			(layer "B.Fab")
		)
		(pad "1" smd custom
			(at 0 -0.4445 90)
			(size 0.1524 0.1524)
			(layers "B.Cu" "B.Mask" "B.Paste")
			(net "P1V26_STBY")
			(options
				(clearance outline)
				(anchor circle)
			)
			(primitives
				(gr_poly
					(pts
						(arc
							(start 0.3048 0.2032)
							(mid 0.275042 0.275042)
							(end 0.2032 0.3048)
						)
						(arc
							(start -0.2032 0.3048)
							(mid -0.275042 0.275042)
							(end -0.3048 0.2032)
						)
						(arc
							(start -0.3048 -0.2032)
							(mid -0.275042 -0.275042)
							(end -0.2032 -0.3048)
						)
						(arc
							(start 0.2032 -0.3048)
							(mid 0.275042 -0.275042)
							(end 0.3048 -0.2032)
						)
					)
					(width 0)
					(fill yes)
				)
			)
		)
		(pad "2" smd custom
			(at 0 0.4445 90)
			(size 0.1524 0.1524)
			(layers "B.Cu" "B.Mask" "B.Paste")
			(net "GND")
			(options
				(clearance outline)
				(anchor circle)
			)
			(primitives
				(gr_poly
					(pts
						(arc
							(start 0.3048 0.2032)
							(mid 0.275042 0.275042)
							(end 0.2032 0.3048)
						)
						(arc
							(start -0.2032 0.3048)
							(mid -0.275042 0.275042)
							(end -0.3048 0.2032)
						)
						(arc
							(start -0.3048 -0.2032)
							(mid -0.275042 -0.275042)
							(end -0.2032 -0.3048)
						)
						(arc
							(start 0.2032 -0.3048)
							(mid 0.275042 -0.275042)
							(end 0.3048 -0.2032)
						)
					)
					(width 0)
					(fill yes)
				)
			)
		)
	)
	(footprint ""
		(layer "B.Cu")
		(at 254.5588 -59.9948 90)
		(property "Reference" "C597"
			(at 0 0 90)
			(layer "B.SilkS")
			(hide yes)
			(effects
				(font
					(size 1.27 1.27)
				)
				(justify mirror)
			)
		)
		(property "Value" "SCD1U16V1KX-1-GP"
			(at 2.8321 -1.7399 90)
			(unlocked yes)
			(layer "B.Fab")
			(hide yes)
			(effects
				(font
					(size 1.016 1.016)
					(thickness 0.1524)
				)
				(justify mirror)
			)
		)
		(property "Device Type" "C0201H13"
			(at 2.8321 -3.2639 90)
			(unlocked yes)
			(layer "B.Fab")
			(hide yes)
			(effects
				(font
					(size 1.016 1.016)
					(thickness 0.1524)
				)
				(justify mirror)
			)
		)
		(duplicate_pad_numbers_are_jumpers no)
		(fp_rect
			(start 0.2794 0.6477)
			(end -0.2794 -0.6477)
			(stroke
				(width 0)
				(type default)
			)
			(fill no)
			(layer "B.CrtYd")
		)
		(fp_rect
			(start 0.2794 0.6477)
			(end -0.2794 -0.6477)
			(stroke
				(width 0)
				(type default)
			)
			(fill no)
			(layer "B.Fab")
		)
		(pad "1" smd custom
			(at 0 -0.2794 270)
			(size 0.0762 0.0762)
			(layers "B.Cu" "B.Mask" "B.Paste")
			(net "DUT_AVD_PCIE")
			(options
				(clearance outline)
				(anchor circle)
			)
			(primitives
				(gr_poly
					(pts
						(arc
							(start 0.1524 0.127)
							(mid 0.137521 0.162921)
							(end 0.1016 0.1778)
						)
						(arc
							(start -0.1016 0.1778)
							(mid -0.137521 0.162921)
							(end -0.1524 0.127)
						)
						(arc
							(start -0.1524 -0.127)
							(mid -0.137521 -0.162921)
							(end -0.1016 -0.1778)
						)
						(arc
							(start 0.1016 -0.1778)
							(mid 0.137521 -0.162921)
							(end 0.1524 -0.127)
						)
					)
					(width 0)
					(fill yes)
				)
			)
		)
		(pad "2" smd custom
			(at 0 0.2794 270)
			(size 0.0762 0.0762)
			(layers "B.Cu" "B.Mask" "B.Paste")
			(net "GND")
			(options
				(clearance outline)
				(anchor circle)
			)
			(primitives
				(gr_poly
					(pts
						(arc
							(start 0.1524 0.127)
							(mid 0.137521 0.162921)
							(end 0.1016 0.1778)
						)
						(arc
							(start -0.1016 0.1778)
							(mid -0.137521 0.162921)
							(end -0.1524 0.127)
						)
						(arc
							(start -0.1524 -0.127)
							(mid -0.137521 -0.162921)
							(end -0.1016 -0.1778)
						)
						(arc
							(start 0.1016 -0.1778)
							(mid 0.137521 -0.162921)
							(end 0.1524 -0.127)
						)
					)
					(width 0)
					(fill yes)
				)
			)
		)
	)
	(footprint ""
		(layer "B.Cu")
		(at 71.9074 -37.8206 90)
		(property "Reference" "PC27"
			(at 0 0 90)
			(layer "B.SilkS")
			(hide yes)
			(effects
				(font
					(size 1.27 1.27)
				)
				(justify mirror)
			)
		)
		(property "Value" "SCD1U50V3KX-GP"
			(at 0 -2.8194 90)
			(unlocked yes)
			(layer "B.Fab")
			(hide yes)
			(effects
				(font
					(size 1.016 1.016)
					(thickness 0.1524)
				)
				(justify mirror)
			)
		)
		(property "Device Type" "C603H36"
			(at 0 -4.3434 90)
			(unlocked yes)
			(layer "B.Fab")
			(hide yes)
			(effects
				(font
					(size 1.016 1.016)
					(thickness 0.1524)
				)
				(justify mirror)
			)
		)
		(duplicate_pad_numbers_are_jumpers no)
		(fp_line
			(start -0.508 0)
			(end 0.508 0)
			(stroke
				(width 0.2032)
				(type default)
			)
			(layer "B.SilkS")
		)
		(fp_rect
			(start 0.5842 1.3335)
			(end -0.5842 -1.3335)
			(stroke
				(width 0)
				(type default)
			)
			(fill no)
			(layer "B.CrtYd")
		)
		(fp_rect
			(start 0.5842 1.3335)
			(end -0.5842 -1.3335)
			(stroke
				(width 0)
				(type default)
			)
			(fill no)
			(layer "B.Fab")
		)
		(pad "1" smd custom
			(at 0 -0.762 270)
			(size 0.2159 0.2159)
			(layers "B.Cu" "B.Mask" "B.Paste")
			(net "P3V3_STBY_VBST_RC")
			(options
				(clearance outline)
				(anchor circle)
			)
			(primitives
				(gr_poly
					(pts
						(arc
							(start -0.3302 0.4318)
							(mid -0.402042 0.402042)
							(end -0.4318 0.3302)
						)
						(arc
							(start -0.4318 -0.3302)
							(mid -0.402042 -0.402042)
							(end -0.3302 -0.4318)
						)
						(arc
							(start 0.3302 -0.4318)
							(mid 0.402042 -0.402042)
							(end 0.4318 -0.3302)
						)
						(arc
							(start 0.4318 0.3302)
							(mid 0.402042 0.402042)
							(end 0.3302 0.4318)
						)
					)
					(width 0)
					(fill yes)
				)
			)
		)
		(pad "2" smd custom
			(at 0 0.762 270)
			(size 0.2159 0.2159)
			(layers "B.Cu" "B.Mask" "B.Paste")
			(net "P3V3_STBY_LL")
			(options
				(clearance outline)
				(anchor circle)
			)
			(primitives
				(gr_poly
					(pts
						(arc
							(start -0.3302 0.4318)
							(mid -0.402042 0.402042)
							(end -0.4318 0.3302)
						)
						(arc
							(start -0.4318 -0.3302)
							(mid -0.402042 -0.402042)
							(end -0.3302 -0.4318)
						)
						(arc
							(start 0.3302 -0.4318)
							(mid 0.402042 -0.402042)
							(end 0.4318 -0.3302)
						)
						(arc
							(start 0.4318 0.3302)
							(mid 0.402042 0.402042)
							(end 0.3302 0.4318)
						)
					)
					(width 0)
					(fill yes)
				)
			)
		)
	)
	(footprint ""
		(layer "B.Cu")
		(at 226.8474 -9.2456 180)
		(property "Reference" "R713"
			(at 0 0 0)
			(layer "B.SilkS")
			(hide yes)
			(effects
				(font
					(size 1.27 1.27)
				)
				(justify mirror)
			)
		)
		(property "Value" "4K7R2F-GP"
			(at -0.064008 -3.993896 180)
			(unlocked yes)
			(layer "B.Fab")
			(hide yes)
			(effects
				(font
					(size 1.016 1.016)
					(thickness 0.1524)
				)
				(justify mirror)
			)
		)
		(property "Device Type" "R402H16"
			(at -0.064008 -5.517896 180)
			(unlocked yes)
			(layer "B.Fab")
			(hide yes)
			(effects
				(font
					(size 1.016 1.016)
					(thickness 0.1524)
				)
				(justify mirror)
			)
		)
		(duplicate_pad_numbers_are_jumpers no)
		(fp_line
			(start 0.508 -0.9398)
			(end 0.508 0.9398)
			(stroke
				(width 0.1524)
				(type default)
			)
			(layer "B.SilkS")
		)
		(fp_line
			(start -0.508 -0.9398)
			(end 0.508 -0.9398)
			(stroke
				(width 0.1524)
				(type default)
			)
			(layer "B.SilkS")
		)
		(fp_rect
			(start 0.508 0.9398)
			(end -0.508 -0.9398)
			(stroke
				(width 0)
				(type default)
			)
			(fill no)
			(layer "B.CrtYd")
		)
		(fp_rect
			(start 0.508 0.9398)
			(end -0.508 -0.9398)
			(stroke
				(width 0)
				(type default)
			)
			(fill no)
			(layer "B.Fab")
		)
		(pad "1" smd custom
			(at 0 -0.4445)
			(size 0.1397 0.1397)
			(layers "B.Cu" "B.Mask" "B.Paste")
			(net "U81_B")
			(options
				(clearance outline)
				(anchor circle)
			)
			(primitives
				(gr_poly
					(pts
						(arc
							(start -0.1778 0.2794)
							(mid -0.249642 0.249642)
							(end -0.2794 0.1778)
						)
						(arc
							(start -0.2794 -0.1778)
							(mid -0.249642 -0.249642)
							(end -0.1778 -0.2794)
						)
						(arc
							(start 0.1778 -0.2794)
							(mid 0.249642 -0.249642)
							(end 0.2794 -0.1778)
						)
						(arc
							(start 0.2794 0.1778)
							(mid 0.249642 0.249642)
							(end 0.1778 0.2794)
						)
					)
					(width 0)
					(fill yes)
				)
			)
		)
		(pad "2" smd custom
			(at 0 0.4445)
			(size 0.1397 0.1397)
			(layers "B.Cu" "B.Mask" "B.Paste")
			(net "P3V3_STBY")
			(options
				(clearance outline)
				(anchor circle)
			)
			(primitives
				(gr_poly
					(pts
						(arc
							(start -0.1778 0.2794)
							(mid -0.249642 0.249642)
							(end -0.2794 0.1778)
						)
						(arc
							(start -0.2794 -0.1778)
							(mid -0.249642 -0.249642)
							(end -0.1778 -0.2794)
						)
						(arc
							(start 0.1778 -0.2794)
							(mid 0.249642 -0.249642)
							(end 0.2794 -0.1778)
						)
						(arc
							(start 0.2794 0.1778)
							(mid 0.249642 0.249642)
							(end 0.1778 0.2794)
						)
					)
					(width 0)
					(fill yes)
				)
			)
		)
	)
	(footprint ""
		(layer "B.Cu")
		(at 63.881 -123.444 90)
		(property "Reference" "R249"
			(at 0 0 90)
			(layer "B.SilkS")
			(hide yes)
			(effects
				(font
					(size 1.27 1.27)
				)
				(justify mirror)
			)
		)
		(property "Value" "0R2J-2-GP"
			(at -0.064008 -3.993896 90)
			(unlocked yes)
			(layer "B.Fab")
			(hide yes)
			(effects
				(font
					(size 1.016 1.016)
					(thickness 0.1524)
				)
				(justify mirror)
			)
		)
		(property "Device Type" "R402H16"
			(at -0.064008 -5.517896 90)
			(unlocked yes)
			(layer "B.Fab")
			(hide yes)
			(effects
				(font
					(size 1.016 1.016)
					(thickness 0.1524)
				)
				(justify mirror)
			)
		)
		(duplicate_pad_numbers_are_jumpers no)
		(fp_line
			(start 0.508 -0.9398)
			(end 0.508 0.9398)
			(stroke
				(width 0.1524)
				(type default)
			)
			(layer "B.SilkS")
		)
		(fp_line
			(start -0.508 -0.9398)
			(end 0.508 -0.9398)
			(stroke
				(width 0.1524)
				(type default)
			)
			(layer "B.SilkS")
		)
		(fp_rect
			(start 0.508 0.9398)
			(end -0.508 -0.9398)
			(stroke
				(width 0)
				(type default)
			)
			(fill no)
			(layer "B.CrtYd")
		)
		(fp_rect
			(start 0.508 0.9398)
			(end -0.508 -0.9398)
			(stroke
				(width 0)
				(type default)
			)
			(fill no)
			(layer "B.Fab")
		)
		(pad "1" smd custom
			(at 0 -0.4445 270)
			(size 0.1397 0.1397)
			(layers "B.Cu" "B.Mask" "B.Paste")
			(net "BMC_I2C6_C_FCB_SCL")
			(options
				(clearance outline)
				(anchor circle)
			)
			(primitives
				(gr_poly
					(pts
						(arc
							(start -0.1778 0.2794)
							(mid -0.249642 0.249642)
							(end -0.2794 0.1778)
						)
						(arc
							(start -0.2794 -0.1778)
							(mid -0.249642 -0.249642)
							(end -0.1778 -0.2794)
						)
						(arc
							(start 0.1778 -0.2794)
							(mid 0.249642 -0.249642)
							(end 0.2794 -0.1778)
						)
						(arc
							(start 0.2794 0.1778)
							(mid 0.249642 0.249642)
							(end 0.1778 0.2794)
						)
					)
					(width 0)
					(fill yes)
				)
			)
		)
		(pad "2" smd custom
			(at 0 0.4445 270)
			(size 0.1397 0.1397)
			(layers "B.Cu" "B.Mask" "B.Paste")
			(net "BMC0_SMB6_CLK")
			(options
				(clearance outline)
				(anchor circle)
			)
			(primitives
				(gr_poly
					(pts
						(arc
							(start -0.1778 0.2794)
							(mid -0.249642 0.249642)
							(end -0.2794 0.1778)
						)
						(arc
							(start -0.2794 -0.1778)
							(mid -0.249642 -0.249642)
							(end -0.1778 -0.2794)
						)
						(arc
							(start 0.1778 -0.2794)
							(mid 0.249642 -0.249642)
							(end 0.2794 -0.1778)
						)
						(arc
							(start 0.2794 0.1778)
							(mid 0.249642 0.249642)
							(end 0.1778 0.2794)
						)
					)
					(width 0)
					(fill yes)
				)
			)
		)
	)
)
